# BASEBOARD_FAB2 (Tioga Pass) — schematic netlist excerpt (pin names and nets, part order shuffled) for the footprints in the layout excerpt that follows; sources: Cadence DE-HDL packaged netlist, KiCad conversion of Wiwynn_Tioga_Pass_MB.brd

C4G26  CAP  0.1UF 25V 10% X7R  pkg 0603LF  page 233 : A = VR_PVPP_GHJ_PHASE ; B = VR_PVPP_GHJ_BOOT_R
R1B2  RES  1.00K 1% CHIP  pkg 0402  page 226 : A = P3V3_STBY ; B = PWRGD_PVDDQ_KLM_R
R6D7  RES  240 1.0% EMPTY  pkg 0402  page 90 : A = PVCCIO_CPU0 ; B = H_CPU0_BMCINIT

(kicad_pcb
	(version 20260206)
	(generator "pcbnew")
	(generator_version "10.0")
	(general
		(thickness 1.6)
		(legacy_teardrops no)
	)
	(paper "A4")
	(title_block
		(title "Wiwynn_Tioga_Pass_MB.brd")
		(comment 1 "Tioga Pass / footprints 608-610 of 4770")
	)
	(layers
		(0 "F.Cu" signal "TOP")
		(4 "In1.Cu" signal "L2GND")
		(6 "In2.Cu" signal "L3")
		(8 "In3.Cu" signal "L4GND")
		(10 "In4.Cu" signal "L5")
		(12 "In5.Cu" signal "L6GND")
		(14 "In6.Cu" signal "L7VCC")
		(16 "In7.Cu" signal "L8VCC")
		(18 "In8.Cu" signal "L9GND")
		(20 "In9.Cu" signal "L10")
		(22 "In10.Cu" signal "L11GND")
		(24 "In11.Cu" signal "L12")
		(26 "In12.Cu" signal "L13GND")
		(2 "B.Cu" signal "BOTTOM")
		(9 "F.Adhes" user "F.Adhesive")
		(11 "B.Adhes" user "B.Adhesive")
		(13 "F.Paste" user "Package Geometry/Pastemask Top")
		(15 "B.Paste" user "Package Geometry/Pastemask Bottom")
		(5 "F.SilkS" user "Ref Des/Silkscreen Top")
		(7 "B.SilkS" user "Ref Des/Silkscreen Bottom")
		(1 "F.Mask" user "Board Geometry/Soldermask Top")
		(3 "B.Mask" user "Board Geometry/Soldermask Bottom")
		(17 "Dwgs.User" user "User.Drawings")
		(19 "Cmts.User" user "User.Comments")
		(21 "Eco1.User" user "User.Eco1")
		(23 "Eco2.User" user "User.Eco2")
		(25 "Edge.Cuts" user "Board Geometry/Outline")
		(27 "Margin" user)
		(31 "F.CrtYd" user "Package Geometry/Place Bound Top")
		(29 "B.CrtYd" user "Package Geometry/Place Bound Bottom")
		(35 "F.Fab" user "Ref Des/Assembly Top")
		(33 "B.Fab" user "Ref Des/Assembly Bottom")
	)
	(footprint ""
		(layer "F.Cu")
		(at -0.60706 -132.54736)
		(property "Reference" "R1B2"
			(at 0 0 0)
			(layer "F.SilkS")
			(hide yes)
			(effects
				(font
					(size 1.27 1.27)
				)
			)
		)
		(property "Value" ""
			(at 0 0 0)
			(layer "F.Fab")
			(effects
				(font
					(size 1.27 1.27)
				)
			)
		)
		(duplicate_pad_numbers_are_jumpers no)
		(fp_rect
			(start -0.2794 0.9906)
			(end 0.2794 -0.1016)
			(stroke
				(width 0)
				(type default)
			)
			(fill no)
			(layer "F.CrtYd")
		)
		(fp_line
			(start -0.2794 -0.1016)
			(end -0.2794 0.9906)
			(stroke
				(width 0.1)
				(type default)
			)
			(layer "F.Fab")
		)
		(fp_line
			(start -0.2794 0.9906)
			(end 0.2794 0.9906)
			(stroke
				(width 0.1)
				(type default)
			)
			(layer "F.Fab")
		)
		(fp_line
			(start 0.2794 -0.1016)
			(end -0.2794 -0.1016)
			(stroke
				(width 0.1)
				(type default)
			)
			(layer "F.Fab")
		)
		(fp_line
			(start 0.2794 0.9906)
			(end 0.2794 -0.1016)
			(stroke
				(width 0.1)
				(type default)
			)
			(layer "F.Fab")
		)
		(pad "1" smd rect
			(at 0 0)
			(size 0.508 0.508)
			(layers "F.Cu" "F.Mask" "F.Paste")
			(net "P3V3_STBY")
		)
		(pad "2" smd rect
			(at 0 0.889)
			(size 0.508 0.508)
			(layers "F.Cu" "F.Mask" "F.Paste")
			(net "PWRGD_PVDDQ_KLM_R")
		)
		(zone
			(layer "F.Cu")
			(hatch none 0.5)
			(connect_pads
				(clearance 0)
			)
			(min_thickness 0.25)
			(keepout
				(tracks not_allowed)
				(vias allowed)
				(pads allowed)
				(copperpour not_allowed)
				(footprints allowed)
			)
			(placement
				(enabled no)
				(sheetname "")
			)
			(fill
				(thermal_gap 0.5)
				(thermal_bridge_width 0.5)
				(island_removal_mode 0)
			)
			(polygon
				(pts
					(xy -0.86106 -131.91236) (xy -0.35306 -131.91236) (xy -0.35306 -132.29336) (xy -0.86106 -132.29336)
				)
			)
		)
		(zone
			(layer "F.Cu")
			(hatch none 0.5)
			(connect_pads
				(clearance 0)
			)
			(min_thickness 0.25)
			(keepout
				(tracks allowed)
				(vias not_allowed)
				(pads allowed)
				(copperpour not_allowed)
				(footprints allowed)
			)
			(placement
				(enabled no)
				(sheetname "")
			)
			(fill
				(thermal_gap 0.5)
				(thermal_bridge_width 0.5)
				(island_removal_mode 0)
			)
			(polygon
				(pts
					(xy -0.86106 -131.91236) (xy -0.35306 -131.91236) (xy -0.35306 -132.29336) (xy -0.86106 -132.29336)
				)
			)
		)
	)
	(footprint ""
		(layer "F.Cu")
		(at 281.178 -74.93 90)
		(property "Reference" "R6D7"
			(at 0 0 90)
			(layer "F.SilkS")
			(hide yes)
			(effects
				(font
					(size 1.27 1.27)
				)
			)
		)
		(property "Value" ""
			(at 0 0 90)
			(layer "F.Fab")
			(effects
				(font
					(size 1.27 1.27)
				)
			)
		)
		(duplicate_pad_numbers_are_jumpers no)
		(fp_rect
			(start -0.2794 -0.1016)
			(end 0.2794 0.9906)
			(stroke
				(width 0)
				(type default)
			)
			(fill no)
			(layer "F.CrtYd")
		)
		(fp_line
			(start 0.2794 -0.1016)
			(end -0.2794 -0.1016)
			(stroke
				(width 0.1)
				(type default)
			)
			(layer "F.Fab")
		)
		(fp_line
			(start -0.2794 -0.1016)
			(end -0.2794 0.9906)
			(stroke
				(width 0.1)
				(type default)
			)
			(layer "F.Fab")
		)
		(fp_line
			(start 0.2794 0.9906)
			(end 0.2794 -0.1016)
			(stroke
				(width 0.1)
				(type default)
			)
			(layer "F.Fab")
		)
		(fp_line
			(start -0.2794 0.9906)
			(end 0.2794 0.9906)
			(stroke
				(width 0.1)
				(type default)
			)
			(layer "F.Fab")
		)
		(pad "1" smd rect
			(at 0 0 90)
			(size 0.508 0.508)
			(layers "F.Cu" "F.Mask" "F.Paste")
			(net "PVCCIO_CPU0")
		)
		(pad "2" smd rect
			(at 0 0.889 90)
			(size 0.508 0.508)
			(layers "F.Cu" "F.Mask" "F.Paste")
			(net "H_CPU0_BMCINIT")
		)
		(zone
			(layer "F.Cu")
			(hatch none 0.5)
			(connect_pads
				(clearance 0)
			)
			(min_thickness 0.25)
			(keepout
				(tracks allowed)
				(vias not_allowed)
				(pads allowed)
				(copperpour not_allowed)
				(footprints allowed)
			)
			(placement
				(enabled no)
				(sheetname "")
			)
			(fill
				(thermal_gap 0.5)
				(thermal_bridge_width 0.5)
				(island_removal_mode 0)
			)
			(polygon
				(pts
					(xy 281.432 -74.676) (xy 281.813 -74.676) (xy 281.813 -75.184) (xy 281.432 -75.184)
				)
			)
		)
		(zone
			(layer "F.Cu")
			(hatch none 0.5)
			(connect_pads
				(clearance 0)
			)
			(min_thickness 0.25)
			(keepout
				(tracks not_allowed)
				(vias allowed)
				(pads allowed)
				(copperpour not_allowed)
				(footprints allowed)
			)
			(placement
				(enabled no)
				(sheetname "")
			)
			(fill
				(thermal_gap 0.5)
				(thermal_bridge_width 0.5)
				(island_removal_mode 0)
			)
			(polygon
				(pts
					(xy 281.432 -74.676) (xy 281.813 -74.676) (xy 281.813 -75.184) (xy 281.432 -75.184)
				)
			)
		)
	)
	(footprint ""
		(layer "F.Cu")
		(at 169.103294 -10.262362 90)
		(property "Reference" "C4G26"
			(at 0 0 90)
			(layer "F.SilkS")
			(hide yes)
			(effects
				(font
					(size 1.27 1.27)
				)
			)
		)
		(property "Value" ""
			(at 0 0 90)
			(layer "F.Fab")
			(effects
				(font
					(size 1.27 1.27)
				)
			)
		)
		(duplicate_pad_numbers_are_jumpers no)
		(fp_rect
			(start 0.4953 1.6002)
			(end -0.4953 -0.2032)
			(stroke
				(width 0)
				(type default)
			)
			(fill no)
			(layer "F.CrtYd")
		)
		(fp_line
			(start 0.4953 -0.2032)
			(end 0.4953 1.6002)
			(stroke
				(width 0.1)
				(type default)
			)
			(layer "F.Fab")
		)
		(fp_line
			(start -0.4953 -0.2032)
			(end 0.4953 -0.2032)
			(stroke
				(width 0.1)
				(type default)
			)
			(layer "F.Fab")
		)
		(fp_line
			(start 0.4953 1.6002)
			(end -0.4953 1.6002)
			(stroke
				(width 0.1)
				(type default)
			)
			(layer "F.Fab")
		)
		(fp_line
			(start -0.4953 1.6002)
			(end -0.4953 -0.2032)
			(stroke
				(width 0.1)
				(type default)
			)
			(layer "F.Fab")
		)
		(pad "1" smd rect
			(at 0 0 90)
			(size 0.762 0.889)
			(layers "F.Cu" "F.Mask" "F.Paste")
			(net "VR_PVPP_GHJ_PHASE")
		)
		(pad "2" smd rect
			(at 0 1.397 90)
			(size 0.762 0.889)
			(layers "F.Cu" "F.Mask" "F.Paste")
			(net "VR_PVPP_GHJ_BOOT_R")
		)
		(zone
			(layer "F.Cu")
			(hatch none 0.5)
			(connect_pads
				(clearance 0)
			)
			(min_thickness 0.25)
			(keepout
				(tracks not_allowed)
				(vias allowed)
				(pads allowed)
				(copperpour not_allowed)
				(footprints allowed)
			)
			(placement
				(enabled no)
				(sheetname "")
			)
			(fill
				(thermal_gap 0.5)
				(thermal_bridge_width 0.5)
				(island_removal_mode 0)
			)
			(polygon
				(pts
					(xy 170.055794 -10.643362) (xy 169.547794 -10.643362) (xy 169.547794 -9.881362) (xy 170.055794 -9.881362)
				)
			)
		)
	)
)
